#ISCELL
  mstr_misc dns *
  *
#ISCELL
  mstr_symbols cad_note *
  *
#ISCELL
  mstr_symbols design_note *
  *
#ISCELL
  mstr_symbols intel_corp_bpage *
  *
#CELL
  mstr_digital adc128d818 *
  page165_i52
#ISCELL
  mstr_standard offpage *
  page165_i53
#ISCELL
  mstr_standard offpage *
  page165_i54
#CELL
  mstr_discrete res *
  page165_i55
#CELL
  mstr_discrete res *
  page165_i56
#CELL
  mstr_discrete res *
  page165_i57
#CELL
  mstr_discrete res *
  page165_i58
#ISCELL
  mstr_symbols gnd *
  page165_i59
#ISCELL
  mstr_symbols gnd *
  page165_i60
#CELL
  dev_discrete cap_a *
  page165_i61
#ISCELL
  mstr_symbols gnd *
  page165_i62
#ISCELL
  mstr_symbols p3v3_stby *
  page165_i63
#ISCELL
  mstr_symbols p3v3_stby *
  page165_i64
#ISCELL
  mstr_symbols p3v3_stby *
  page165_i65
#ISCELL
  mstr_symbols gnd *
  page165_i66
#CELL
  mstr_discrete cap *
  page165_i67
#ISCELL
  mstr_symbols gnd *
  page165_i68
#CELL
  mstr_discrete res *
  page165_i69
#ISCELL
  mstr_symbols p3v3_stby *
  page165_i70
#ISCELL
  mstr_standard offpage *
  page165_i71
#ISCELL
  mstr_standard offpage *
  page165_i72
#ISCELL
  mstr_standard offpage *
  page165_i73
#ISCELL
  mstr_standard offpage *
  page165_i74
#ISCELL
  mstr_standard offpage *
  page165_i75
#ISCELL
  mstr_standard offpage *
  page165_i76
#ISCELL
  mstr_standard offpage *
  page165_i77
#ISCELL
  mstr_standard offpage *
  page165_i78
#CELL
  mstr_discrete ferrite *
  page165_i79
#ISCELL
  mstr_standard offpage *
  page165_i80
#CELL
  mstr_discrete res *
  page165_i81
